#ISCELL
  mstr_misc dns *
  *
#ISCELL
  pure_quanta quanta_title_block_c *
  *
#ISCELL
  pure_quanta_power bom_note *
  *
#ISCELL
  standard offpage *
  page295_i121
#CELL
  pure_quanta q_res *
  page295_i122
#ISCELL
  pure_quanta_power universal_power *
  page295_i123
#ISCELL
  pure_quanta_power universal_gnd *
  page295_i124
#CELL
  pure_quanta q_cap *
  page295_i125
#ISCELL
  pure_quanta_power universal_gnd *
  page295_i128
#CELL
  pure_quanta isl28022frzt *
  page295_i129
#CELL
  pure_quanta q_res *
  page295_i132
#CELL
  pure_quanta q_cap *
  page295_i133
#CELL
  pure_quanta q_res *
  page295_i134
#CELL
  pure_quanta q_res *
  page295_i135
#CELL
  pure_quanta q_res *
  page295_i136
#ISCELL
  pure_quanta_power universal_gnd *
  page295_i137
#ISCELL
  standard offpage *
  page295_i138
#ISCELL
  standard offpage *
  page295_i139
#ISCELL
  pure_quanta_power universal_power *
  page295_i140
#CELL
  pure_quanta q_cap *
  page295_i142
#ISCELL
  pure_quanta_power universal_gnd *
  page295_i143
#CELL
  pure_quanta q_res *
  page295_i144
#ISCELL
  pure_quanta_power universal_power *
  page295_i145
#CELL
  pure_quanta q_res *
  page295_i146
#ISCELL
  pure_quanta_power universal_power *
  page295_i147
#ISCELL
  pure_quanta_power universal_power *
  page295_i148
#CELL
  pure_quanta q_res *
  page295_i149
#ISCELL
  pure_quanta_power universal_power *
  page295_i150
#CELL
  pure_quanta q_res *
  page295_i151
#CELL
  pure_quanta q_res *
  page295_i152
#CELL
  pure_quanta q_res *
  page295_i153
#CELL
  pure_quanta q_res *
  page295_i154
#CELL
  pure_quanta q_res *
  page295_i155
#CELL
  pure_quanta isl28022frzt *
  page295_i30
#CELL
  pure_quanta q_res *
  page295_i31
#ISCELL
  standard offpage *
  page295_i32
#ISCELL
  pure_quanta_power universal_power *
  page295_i33
#CELL
  pure_quanta q_cap *
  page295_i34
#CELL
  pure_quanta q_res *
  page295_i35
#ISCELL
  pure_quanta_power universal_gnd *
  page295_i36
#ISCELL
  pure_quanta_power universal_gnd *
  page295_i37
#CELL
  pure_quanta q_res *
  page295_i40
#CELL
  pure_quanta q_res *
  page295_i41
#CELL
  pure_quanta q_res *
  page295_i43
#ISCELL
  pure_quanta_power universal_gnd *
  page295_i45
#ISCELL
  standard offpage *
  page295_i46
#ISCELL
  standard offpage *
  page295_i47
#ISCELL
  pure_quanta_power universal_gnd *
  page295_i49
#CELL
  pure_quanta q_cap *
  page295_i50
#CELL
  pure_quanta q_cap *
  page295_i77
#ISCELL
  pure_quanta_power universal_power *
  page295_i79
#ISCELL
  pure_quanta_power universal_power *
  page295_i80
#ISCELL
  pure_quanta_power universal_power *
  page295_i81
#ISCELL
  pure_quanta_power universal_power *
  page295_i87
#CELL
  pure_quanta q_res *
  page295_i88
#CELL
  pure_quanta q_res *
  page295_i89
#CELL
  pure_quanta q_res *
  page295_i93
